FILE_TYPE = CONNECTIVITY;
{Allegro Design Entry HDL 16.6-p007 (v16-6-112F) 10/10/2012}
"PAGE_NUMBER" = 68;
0"NC";
1"UPI_CPU1_CPU0_P1P1_DP<19..0>";
2"UPI_CPU1_CPU0_P1P1_DN<19..0>";
3"UPI_CPU0_CPU1_P1P1_DP<19..0>";
4"UPI_CPU0_CPU1_P1P1_DN<19..0>";
5"UPI_CPU0_CPU1_P1P1_DP<4>";
6"UPI_CPU0_CPU1_P1P1_DN<11>";
7"UPI_CPU0_CPU1_P1P1_DP<5>";
8"UPI_CPU1_CPU0_P1P1_DN<8>";
9"UPI_CPU0_CPU1_P1P1_DP<0>";
10"UPI_CPU0_CPU1_P1P1_DN<1>";
11"UPI_CPU0_CPU1_P1P1_DN<2>";
12"UPI_CPU0_CPU1_P1P1_DN<3>";
13"UPI_CPU0_CPU1_P1P1_DN<4>";
14"UPI_CPU0_CPU1_P1P1_DN<5>";
15"UPI_CPU0_CPU1_P1P1_DN<6>";
16"UPI_CPU0_CPU1_P1P1_DN<7>";
17"UPI_CPU0_CPU1_P1P1_DN<0>";
18"UPI_CPU0_CPU1_P1P1_DP<1>";
19"UPI_CPU0_CPU1_P1P1_DP<2>";
20"UPI_CPU0_CPU1_P1P1_DP<3>";
21"UPI_CPU0_CPU1_P1P1_DP<6>";
22"UPI_CPU0_CPU1_P1P1_DP<7>";
23"UPI_CPU0_CPU1_P1P1_DN<8>";
24"UPI_CPU0_CPU1_P1P1_DP<9>";
25"UPI_CPU0_CPU1_P1P1_DP<10>";
26"UPI_CPU0_CPU1_P1P1_DN<12>";
27"UPI_CPU0_CPU1_P1P1_DN<13>";
28"UPI_CPU0_CPU1_P1P1_DP<14>";
29"UPI_CPU0_CPU1_P1P1_DP<15>";
30"UPI_CPU0_CPU1_P1P1_DP<16>";
31"UPI_CPU0_CPU1_P1P1_DP<17>";
32"UPI_CPU0_CPU1_P1P1_DN<18>";
33"UPI_CPU0_CPU1_P1P1_DN<19>";
34"UPI_CPU0_CPU1_P1P1_DP<8>";
35"UPI_CPU0_CPU1_P1P1_DN<9>";
36"UPI_CPU0_CPU1_P1P1_DN<10>";
37"UPI_CPU0_CPU1_P1P1_DP<11>";
38"UPI_CPU0_CPU1_P1P1_DP<12>";
39"UPI_CPU0_CPU1_P1P1_DP<13>";
40"UPI_CPU0_CPU1_P1P1_DN<14>";
41"UPI_CPU0_CPU1_P1P1_DN<15>";
42"UPI_CPU0_CPU1_P1P1_DN<16>";
43"UPI_CPU0_CPU1_P1P1_DN<17>";
44"UPI_CPU0_CPU1_P1P1_DP<18>";
45"UPI_CPU0_CPU1_P1P1_DP<19>";
46"UPI_CPU1_CPU0_P1P1_DP<0>";
47"UPI_CPU1_CPU0_P1P1_DP<1>";
48"UPI_CPU1_CPU0_P1P1_DN<2>";
49"UPI_CPU1_CPU0_P1P1_DN<3>";
50"UPI_CPU1_CPU0_P1P1_DN<4>";
51"UPI_CPU1_CPU0_P1P1_DN<5>";
52"UPI_CPU1_CPU0_P1P1_DP<6>";
53"UPI_CPU1_CPU0_P1P1_DP<7>";
54"UPI_CPU1_CPU0_P1P1_DN<0>";
55"UPI_CPU1_CPU0_P1P1_DN<1>";
56"UPI_CPU1_CPU0_P1P1_DP<2>";
57"UPI_CPU1_CPU0_P1P1_DP<3>";
58"UPI_CPU1_CPU0_P1P1_DP<4>";
59"UPI_CPU1_CPU0_P1P1_DP<5>";
60"UPI_CPU1_CPU0_P1P1_DN<6>";
61"UPI_CPU1_CPU0_P1P1_DN<7>";
62"UPI_CPU1_CPU0_P1P1_DP<9>";
63"UPI_CPU1_CPU0_P1P1_DP<10>";
64"UPI_CPU1_CPU0_P1P1_DN<11>";
65"UPI_CPU1_CPU0_P1P1_DP<12>";
66"UPI_CPU1_CPU0_P1P1_DP<13>";
67"UPI_CPU1_CPU0_P1P1_DP<14>";
68"UPI_CPU1_CPU0_P1P1_DP<15>";
69"UPI_CPU1_CPU0_P1P1_DP<16>";
70"UPI_CPU1_CPU0_P1P1_DP<17>";
71"UPI_CPU1_CPU0_P1P1_DN<18>";
72"UPI_CPU1_CPU0_P1P1_DN<19>";
73"UPI_CPU1_CPU0_P1P1_DP<8>";
74"UPI_CPU1_CPU0_P1P1_DN<9>";
75"UPI_CPU1_CPU0_P1P1_DN<10>";
76"UPI_CPU1_CPU0_P1P1_DP<11>";
77"UPI_CPU1_CPU0_P1P1_DN<12>";
78"UPI_CPU1_CPU0_P1P1_DN<13>";
79"UPI_CPU1_CPU0_P1P1_DN<14>";
80"UPI_CPU1_CPU0_P1P1_DN<15>";
81"UPI_CPU1_CPU0_P1P1_DN<16>";
82"UPI_CPU1_CPU0_P1P1_DN<17>";
83"UPI_CPU1_CPU0_P1P1_DP<18>";
84"UPI_CPU1_CPU0_P1P1_DP<19>";
%"TAP"
"1","(-5725,1900)","2","mstr_standard","I10";
;
CDS_LIB"mstr_standard"
BODY_TYPE"PLUMBING"
HDL_TAP"TRUE";
"B \NAC \NWC"4;
"S \NAC"
BN"5"14;
%"TAP"
"1","(-2950,1700)","0","mstr_standard","I100";
;
CDS_LIB"mstr_standard"
BODY_TYPE"PLUMBING"
HDL_TAP"TRUE";
"B \NAC \NWC"1;
"S \NAC"
BN"1"47;
%"TAP"
"1","(-2950,2950)","0","mstr_standard","I101";
;
CDS_LIB"mstr_standard"
BODY_TYPE"PLUMBING"
HDL_TAP"TRUE";
"B \NAC \NWC"1;
"S \NAC"
BN"5"59;
%"TAP"
"1","(-2950,1950)","0","mstr_standard","I102";
;
CDS_LIB"mstr_standard"
BODY_TYPE"PLUMBING"
HDL_TAP"TRUE";
"B \NAC \NWC"1;
"S \NAC"
BN"6"52;
%"TAP"
"1","(-2950,2000)","0","mstr_standard","I103";
;
CDS_LIB"mstr_standard"
BODY_TYPE"PLUMBING"
HDL_TAP"TRUE";
"B \NAC \NWC"1;
"S \NAC"
BN"7"53;
%"TAP"
"1","(-2950,2050)","0","mstr_standard","I104";
;
CDS_LIB"mstr_standard"
BODY_TYPE"PLUMBING"
HDL_TAP"TRUE";
"B \NAC \NWC"1;
"S \NAC"
BN"8"73;
%"TAP"
"1","(-2950,3150)","0","mstr_standard","I105";
;
CDS_LIB"mstr_standard"
BODY_TYPE"PLUMBING"
HDL_TAP"TRUE";
"B \NAC \NWC"1;
"S \NAC"
BN"9"62;
%"TAP"
"1","(-2950,2200)","0","mstr_standard","I106";
;
CDS_LIB"mstr_standard"
BODY_TYPE"PLUMBING"
HDL_TAP"TRUE";
"B \NAC \NWC"1;
"S \NAC"
BN"11"76;
%"TAP"
"1","(-2950,3350)","0","mstr_standard","I107";
;
CDS_LIB"mstr_standard"
BODY_TYPE"PLUMBING"
HDL_TAP"TRUE";
"B \NAC \NWC"1;
"S \NAC"
BN"13"66;
%"TAP"
"1","(-2950,3400)","0","mstr_standard","I108";
;
CDS_LIB"mstr_standard"
BODY_TYPE"PLUMBING"
HDL_TAP"TRUE";
"B \NAC \NWC"1;
"S \NAC"
BN"14"67;
%"TAP"
"1","(-2950,3450)","0","mstr_standard","I109";
;
CDS_LIB"mstr_standard"
BODY_TYPE"PLUMBING"
HDL_TAP"TRUE";
"B \NAC \NWC"1;
"S \NAC"
BN"15"68;
%"TAP"
"1","(-5725,2000)","2","mstr_standard","I11";
;
CDS_LIB"mstr_standard"
BODY_TYPE"PLUMBING"
HDL_TAP"TRUE";
"B \NAC \NWC"4;
"S \NAC"
BN"7"16;
%"TAP"
"1","(-2950,2550)","0","mstr_standard","I110";
;
CDS_LIB"mstr_standard"
BODY_TYPE"PLUMBING"
HDL_TAP"TRUE";
"B \NAC \NWC"1;
"S \NAC"
BN"18"83;
%"TAP"
"1","(-2950,2600)","0","mstr_standard","I111";
;
CDS_LIB"mstr_standard"
BODY_TYPE"PLUMBING"
HDL_TAP"TRUE";
"B \NAC \NWC"1;
"S \NAC"
BN"19"84;
%"TAP"
"1","(-2625,2700)","0","mstr_standard","I112";
;
CDS_LIB"mstr_standard"
BODY_TYPE"PLUMBING"
HDL_TAP"TRUE";
"B \NAC \NWC"2;
"S \NAC"
BN"0"54;
%"TAP"
"1","(-2625,2750)","0","mstr_standard","I113";
;
CDS_LIB"mstr_standard"
BODY_TYPE"PLUMBING"
HDL_TAP"TRUE";
"B \NAC \NWC"2;
"S \NAC"
BN"1"55;
%"TAP"
"1","(-2625,1900)","0","mstr_standard","I114";
;
CDS_LIB"mstr_standard"
BODY_TYPE"PLUMBING"
HDL_TAP"TRUE";
"B \NAC \NWC"2;
"S \NAC"
BN"5"51;
%"TAP"
"1","(-2625,3000)","0","mstr_standard","I115";
;
CDS_LIB"mstr_standard"
BODY_TYPE"PLUMBING"
HDL_TAP"TRUE";
"B \NAC \NWC"2;
"S \NAC"
BN"6"60;
%"TAP"
"1","(-2625,3050)","0","mstr_standard","I116";
;
CDS_LIB"mstr_standard"
BODY_TYPE"PLUMBING"
HDL_TAP"TRUE";
"B \NAC \NWC"2;
"S \NAC"
BN"7"61;
%"TAP"
"1","(-2625,3100)","0","mstr_standard","I117";
;
CDS_LIB"mstr_standard"
BODY_TYPE"PLUMBING"
HDL_TAP"TRUE";
"B \NAC \NWC"2;
"S \NAC"
BN"8"8;
%"TAP"
"1","(-2625,2100)","0","mstr_standard","I118";
;
CDS_LIB"mstr_standard"
BODY_TYPE"PLUMBING"
HDL_TAP"TRUE";
"B \NAC \NWC"2;
"S \NAC"
BN"9"74;
%"TAP"
"1","(-2625,3250)","0","mstr_standard","I119";
;
CDS_LIB"mstr_standard"
BODY_TYPE"PLUMBING"
HDL_TAP"TRUE";
"B \NAC \NWC"2;
"S \NAC"
BN"11"64;
%"TAP"
"1","(-2625,2300)","0","mstr_standard","I120";
;
CDS_LIB"mstr_standard"
BODY_TYPE"PLUMBING"
HDL_TAP"TRUE";
"B \NAC \NWC"2;
"S \NAC"
BN"13"78;
%"TAP"
"1","(-2625,2350)","0","mstr_standard","I121";
;
CDS_LIB"mstr_standard"
BODY_TYPE"PLUMBING"
HDL_TAP"TRUE";
"B \NAC \NWC"2;
"S \NAC"
BN"14"79;
%"TAP"
"1","(-2625,2400)","0","mstr_standard","I122";
;
CDS_LIB"mstr_standard"
BODY_TYPE"PLUMBING"
HDL_TAP"TRUE";
"B \NAC \NWC"2;
"S \NAC"
BN"15"80;
%"TAP"
"1","(-2625,3600)","0","mstr_standard","I123";
;
CDS_LIB"mstr_standard"
BODY_TYPE"PLUMBING"
HDL_TAP"TRUE";
"B \NAC \NWC"2;
"S \NAC"
BN"18"71;
%"TAP"
"1","(-2625,3650)","0","mstr_standard","I124";
;
CDS_LIB"mstr_standard"
BODY_TYPE"PLUMBING"
HDL_TAP"TRUE";
"B \NAC \NWC"2;
"S \NAC"
BN"19"72;
%"SKX_EXT_B"
"14","(-4100,2650)","0","chpset_lib","I125";
;
CDS_SEC"14"
LOCATION"U2D1"
PART_NUMBER"TBD"
MATERIAL"IC"
PACK_TYPE"BGA1"
SEC_TYPE"BGA1"
CDS_LIB"chpset_lib"
SEC"14"
CDS_LOCATION"U2D1";
"UPI1_TX_DP<0>"
$PN"P3"54;
"UPI1_TX_DP<1>"
$PN"K3"55;
"UPI1_TX_DP<2>"
$PN"M5"56;
"UPI1_TX_DP<3>"
$PN"H5"57;
"UPI1_TX_DP<4>"
$PN"F7"58;
"UPI1_TX_DP<5>"
$PN"K7"59;
"UPI1_TX_DP<6>"
$PN"J8"60;
"UPI1_TX_DP<7>"
$PN"F9"61;
"UPI1_TX_DP<8>"
$PN"E10"8;
"UPI1_TX_DP<9>"
$PN"H9"62;
"UPI1_TX_DP<10>"
$PN"G12"63;
"UPI1_TX_DP<11>"
$PN"F13"64;
"UPI1_TX_DP<12>"
$PN"E14"65;
"UPI1_TX_DP<13>"
$PN"H15"66;
"UPI1_TX_DP<14>"
$PN"G16"67;
"UPI1_TX_DP<15>"
$PN"L18"68;
"UPI1_TX_DP<16>"
$PN"J18"69;
"UPI1_TX_DP<17>"
$PN"H19"70;
"UPI1_TX_DP<18>"
$PN"G20"71;
"UPI1_TX_DP<19>"
$PN"K21"72;
"UPI1_TX_DN<0>"
$PN"M3"46;
"UPI1_TX_DN<1>"
$PN"L4"47;
"UPI1_TX_DN<2>"
$PN"K5"48;
"UPI1_TX_DN<3>"
$PN"J6"49;
"UPI1_TX_DN<4>"
$PN"G6"50;
"UPI1_TX_DN<5>"
$PN"H7"51;
"UPI1_TX_DN<6>"
$PN"K9"52;
"UPI1_TX_DN<7>"
$PN"D9"53;
"UPI1_TX_DN<8>"
$PN"F11"73;
"UPI1_TX_DN<9>"
$PN"G10"74;
"UPI1_TX_DN<10>"
$PN"E12"75;
"UPI1_TX_DN<11>"
$PN"G14"76;
"UPI1_TX_DN<12>"
$PN"D15"77;
"UPI1_TX_DN<13>"
$PN"F15"78;
"UPI1_TX_DN<14>"
$PN"H17"79;
"UPI1_TX_DN<15>"
$PN"K19"80;
"UPI1_TX_DN<16>"
$PN"G18"81;
"UPI1_TX_DN<17>"
$PN"J20"82;
"UPI1_TX_DN<18>"
$PN"F21"83;
"UPI1_TX_DN<19>"
$PN"H21"84;
"UPI1_RX_DP<0>"
$PN"R6"17;
"UPI1_RX_DP<1>"
$PN"T7"18;
"UPI1_RX_DP<2>"
$PN"U8"19;
"UPI1_RX_DP<3>"
$PN"R8"20;
"UPI1_RX_DP<4>"
$PN"N10"5;
"UPI1_RX_DP<5>"
$PN"U10"7;
"UPI1_RX_DP<6>"
$PN"T11"21;
"UPI1_RX_DP<7>"
$PN"N12"22;
"UPI1_RX_DP<8>"
$PN"M13"23;
"UPI1_RX_DP<9>"
$PN"P13"24;
"UPI1_RX_DP<10>"
$PN"T15"25;
"UPI1_RX_DP<11>"
$PN"N16"6;
"UPI1_RX_DP<12>"
$PN"W16"26;
"UPI1_RX_DP<13>"
$PN"V17"27;
"UPI1_RX_DP<14>"
$PN"P19"28;
"UPI1_RX_DP<15>"
$PN"T19"29;
"UPI1_RX_DP<16>"
$PN"T21"30;
"UPI1_RX_DP<17>"
$PN"Y19"31;
"UPI1_RX_DP<18>"
$PN"W20"32;
"UPI1_RX_DP<19>"
$PN"AA20"33;
"UPI1_RX_DN<0>"
$PN"T5"9;
"UPI1_RX_DN<1>"
$PN"P7"10;
"UPI1_RX_DN<2>"
$PN"V7"11;
"UPI1_RX_DN<3>"
$PN"T9"12;
"UPI1_RX_DN<4>"
$PN"P9"13;
"UPI1_RX_DN<5>"
$PN"R10"14;
"UPI1_RX_DN<6>"
$PN"U12"15;
"UPI1_RX_DN<7>"
$PN"L12"16;
"UPI1_RX_DN<8>"
$PN"N14"34;
"UPI1_RX_DN<9>"
$PN"R12"35;
"UPI1_RX_DN<10>"
$PN"R16"36;
"UPI1_RX_DN<11>"
$PN"P17"37;
"UPI1_RX_DN<12>"
$PN"U16"38;
"UPI1_RX_DN<13>"
$PN"W18"39;
"UPI1_RX_DN<14>"
$PN"R20"40;
"UPI1_RX_DN<15>"
$PN"U18"41;
"UPI1_RX_DN<16>"
$PN"P21"42;
"UPI1_RX_DN<17>"
$PN"V19"43;
"UPI1_RX_DN<18>"
$PN"Y21"44;
"UPI1_RX_DN<19>"
$PN"AB19"45;
%"TAP"
"1","(-5725,2100)","2","mstr_standard","I13";
;
CDS_LIB"mstr_standard"
BODY_TYPE"PLUMBING"
HDL_TAP"TRUE";
"B \NAC \NWC"4;
"S \NAC"
BN"9"35;
%"TAP"
"1","(-5725,2150)","2","mstr_standard","I14";
;
CDS_LIB"mstr_standard"
BODY_TYPE"PLUMBING"
HDL_TAP"TRUE";
"B \NAC \NWC"4;
"S \NAC"
BN"10"36;
%"TAP"
"1","(-5725,2350)","2","mstr_standard","I18";
;
CDS_LIB"mstr_standard"
BODY_TYPE"PLUMBING"
HDL_TAP"TRUE";
"B \NAC \NWC"4;
"S \NAC"
BN"14"40;
%"TAP"
"1","(-5725,2500)","2","mstr_standard","I21";
;
CDS_LIB"mstr_standard"
BODY_TYPE"PLUMBING"
HDL_TAP"TRUE";
"B \NAC \NWC"4;
"S \NAC"
BN"17"43;
%"TAP"
"1","(-5725,3600)","2","mstr_standard","I22";
;
CDS_LIB"mstr_standard"
BODY_TYPE"PLUMBING"
HDL_TAP"TRUE";
"B \NAC \NWC"4;
"S \NAC"
BN"18"32;
%"TAP"
"1","(-5275,2800)","2","mstr_standard","I26";
;
CDS_LIB"mstr_standard"
BODY_TYPE"PLUMBING"
HDL_TAP"TRUE";
"B \NAC \NWC"3;
"S \NAC"
BN"2"19;
%"TAP"
"1","(-5275,2850)","2","mstr_standard","I27";
;
CDS_LIB"mstr_standard"
BODY_TYPE"PLUMBING"
HDL_TAP"TRUE";
"B \NAC \NWC"3;
"S \NAC"
BN"3"20;
%"TAP"
"1","(-5275,2900)","2","mstr_standard","I28";
;
CDS_LIB"mstr_standard"
BODY_TYPE"PLUMBING"
HDL_TAP"TRUE";
"B \NAC \NWC"3;
"S \NAC"
BN"4"5;
%"TAP"
"1","(-5275,2950)","2","mstr_standard","I29";
;
CDS_LIB"mstr_standard"
BODY_TYPE"PLUMBING"
HDL_TAP"TRUE";
"B \NAC \NWC"3;
"S \NAC"
BN"5"7;
%"TAP"
"1","(-5275,3000)","2","mstr_standard","I30";
;
CDS_LIB"mstr_standard"
BODY_TYPE"PLUMBING"
HDL_TAP"TRUE";
"B \NAC \NWC"3;
"S \NAC"
BN"6"21;
%"TAP"
"1","(-5275,3050)","2","mstr_standard","I31";
;
CDS_LIB"mstr_standard"
BODY_TYPE"PLUMBING"
HDL_TAP"TRUE";
"B \NAC \NWC"3;
"S \NAC"
BN"7"22;
%"TAP"
"1","(-5275,2050)","2","mstr_standard","I32";
;
CDS_LIB"mstr_standard"
BODY_TYPE"PLUMBING"
HDL_TAP"TRUE";
"B \NAC \NWC"3;
"S \NAC"
BN"8"34;
%"TAP"
"1","(-5275,3150)","2","mstr_standard","I33";
;
CDS_LIB"mstr_standard"
BODY_TYPE"PLUMBING"
HDL_TAP"TRUE";
"B \NAC \NWC"3;
"S \NAC"
BN"9"24;
%"TAP"
"1","(-5275,3200)","2","mstr_standard","I34";
;
CDS_LIB"mstr_standard"
BODY_TYPE"PLUMBING"
HDL_TAP"TRUE";
"B \NAC \NWC"3;
"S \NAC"
BN"10"25;
%"TAP"
"1","(-5275,2200)","2","mstr_standard","I35";
;
CDS_LIB"mstr_standard"
BODY_TYPE"PLUMBING"
HDL_TAP"TRUE";
"B \NAC \NWC"3;
"S \NAC"
BN"11"37;
%"TAP"
"1","(-5275,2250)","2","mstr_standard","I36";
;
CDS_LIB"mstr_standard"
BODY_TYPE"PLUMBING"
HDL_TAP"TRUE";
"B \NAC \NWC"3;
"S \NAC"
BN"12"38;
%"TAP"
"1","(-5275,2300)","2","mstr_standard","I37";
;
CDS_LIB"mstr_standard"
BODY_TYPE"PLUMBING"
HDL_TAP"TRUE";
"B \NAC \NWC"3;
"S \NAC"
BN"13"39;
%"TAP"
"1","(-5275,3400)","2","mstr_standard","I38";
;
CDS_LIB"mstr_standard"
BODY_TYPE"PLUMBING"
HDL_TAP"TRUE";
"B \NAC \NWC"3;
"S \NAC"
BN"14"28;
%"TAP"
"1","(-5275,3450)","2","mstr_standard","I39";
;
CDS_LIB"mstr_standard"
BODY_TYPE"PLUMBING"
HDL_TAP"TRUE";
"B \NAC \NWC"3;
"S \NAC"
BN"15"29;
%"TAP"
"1","(-5275,3500)","2","mstr_standard","I40";
;
CDS_LIB"mstr_standard"
BODY_TYPE"PLUMBING"
HDL_TAP"TRUE";
"B \NAC \NWC"3;
"S \NAC"
BN"16"30;
%"TAP"
"1","(-5275,3550)","2","mstr_standard","I41";
;
CDS_LIB"mstr_standard"
BODY_TYPE"PLUMBING"
HDL_TAP"TRUE";
"B \NAC \NWC"3;
"S \NAC"
BN"17"31;
%"TAP"
"1","(-5275,2550)","2","mstr_standard","I42";
;
CDS_LIB"mstr_standard"
BODY_TYPE"PLUMBING"
HDL_TAP"TRUE";
"B \NAC \NWC"3;
"S \NAC"
BN"18"44;
%"TAP"
"1","(-5275,2600)","2","mstr_standard","I43";
;
CDS_LIB"mstr_standard"
BODY_TYPE"PLUMBING"
HDL_TAP"TRUE";
"B \NAC \NWC"3;
"S \NAC"
BN"19"45;
%"TAP"
"1","(-2625,1800)","0","mstr_standard","I46";
;
CDS_LIB"mstr_standard"
BODY_TYPE"PLUMBING"
HDL_TAP"TRUE";
"B \NAC \NWC"2;
"S \NAC"
BN"3"49;
%"TAP"
"1","(-2625,1750)","0","mstr_standard","I47";
;
CDS_LIB"mstr_standard"
BODY_TYPE"PLUMBING"
HDL_TAP"TRUE";
"B \NAC \NWC"2;
"S \NAC"
BN"2"48;
%"TAP"
"1","(-2625,1850)","0","mstr_standard","I48";
;
CDS_LIB"mstr_standard"
BODY_TYPE"PLUMBING"
HDL_TAP"TRUE";
"B \NAC \NWC"2;
"S \NAC"
BN"4"50;
%"TAP"
"1","(-5725,1800)","2","mstr_standard","I5";
;
CDS_LIB"mstr_standard"
BODY_TYPE"PLUMBING"
HDL_TAP"TRUE";
"B \NAC \NWC"4;
"S \NAC"
BN"3"12;
%"TAP"
"1","(-2625,2150)","0","mstr_standard","I54";
;
CDS_LIB"mstr_standard"
BODY_TYPE"PLUMBING"
HDL_TAP"TRUE";
"B \NAC \NWC"2;
"S \NAC"
BN"10"75;
%"TAP"
"1","(-2625,2250)","0","mstr_standard","I56";
;
CDS_LIB"mstr_standard"
BODY_TYPE"PLUMBING"
HDL_TAP"TRUE";
"B \NAC \NWC"2;
"S \NAC"
BN"12"77;
%"TAP"
"1","(-5725,1750)","2","mstr_standard","I6";
;
CDS_LIB"mstr_standard"
BODY_TYPE"PLUMBING"
HDL_TAP"TRUE";
"B \NAC \NWC"4;
"S \NAC"
BN"2"11;
%"TAP"
"1","(-2625,2500)","0","mstr_standard","I60";
;
CDS_LIB"mstr_standard"
BODY_TYPE"PLUMBING"
HDL_TAP"TRUE";
"B \NAC \NWC"2;
"S \NAC"
BN"17"82;
%"TAP"
"1","(-2625,2450)","0","mstr_standard","I61";
;
CDS_LIB"mstr_standard"
BODY_TYPE"PLUMBING"
HDL_TAP"TRUE";
"B \NAC \NWC"2;
"S \NAC"
BN"16"81;
%"TAP"
"1","(-2950,2800)","0","mstr_standard","I66";
;
CDS_LIB"mstr_standard"
BODY_TYPE"PLUMBING"
HDL_TAP"TRUE";
"B \NAC \NWC"1;
"S \NAC"
BN"2"56;
%"TAP"
"1","(-2950,2850)","0","mstr_standard","I67";
;
CDS_LIB"mstr_standard"
BODY_TYPE"PLUMBING"
HDL_TAP"TRUE";
"B \NAC \NWC"1;
"S \NAC"
BN"3"57;
%"TAP"
"1","(-2950,2900)","0","mstr_standard","I69";
;
CDS_LIB"mstr_standard"
BODY_TYPE"PLUMBING"
HDL_TAP"TRUE";
"B \NAC \NWC"1;
"S \NAC"
BN"4"58;
%"TAP"
"1","(-2950,3200)","0","mstr_standard","I74";
;
CDS_LIB"mstr_standard"
BODY_TYPE"PLUMBING"
HDL_TAP"TRUE";
"B \NAC \NWC"1;
"S \NAC"
BN"10"63;
%"TAP"
"1","(-2950,3300)","0","mstr_standard","I76";
;
CDS_LIB"mstr_standard"
BODY_TYPE"PLUMBING"
HDL_TAP"TRUE";
"B \NAC \NWC"1;
"S \NAC"
BN"12"65;
%"TAP"
"1","(-2950,3500)","0","mstr_standard","I80";
;
CDS_LIB"mstr_standard"
BODY_TYPE"PLUMBING"
HDL_TAP"TRUE";
"B \NAC \NWC"1;
"S \NAC"
BN"16"69;
%"TAP"
"1","(-2950,3550)","0","mstr_standard","I82";
;
CDS_LIB"mstr_standard"
BODY_TYPE"PLUMBING"
HDL_TAP"TRUE";
"B \NAC \NWC"1;
"S \NAC"
BN"17"70;
%"TAP"
"1","(-5725,2700)","2","mstr_standard","I86";
;
CDS_LIB"mstr_standard"
BODY_TYPE"PLUMBING"
HDL_TAP"TRUE";
"B \NAC \NWC"4;
"S \NAC"
BN"0"17;
%"TAP"
"1","(-5725,1700)","2","mstr_standard","I87";
;
CDS_LIB"mstr_standard"
BODY_TYPE"PLUMBING"
HDL_TAP"TRUE";
"B \NAC \NWC"4;
"S \NAC"
BN"1"10;
%"TAP"
"1","(-5275,1650)","2","mstr_standard","I88";
;
CDS_LIB"mstr_standard"
BODY_TYPE"PLUMBING"
HDL_TAP"TRUE";
"B \NAC \NWC"3;
"S \NAC"
BN"0"9;
%"TAP"
"1","(-5275,2750)","2","mstr_standard","I89";
;
CDS_LIB"mstr_standard"
BODY_TYPE"PLUMBING"
HDL_TAP"TRUE";
"B \NAC \NWC"3;
"S \NAC"
BN"1"18;
%"TAP"
"1","(-5725,1850)","2","mstr_standard","I90";
;
CDS_LIB"mstr_standard"
BODY_TYPE"PLUMBING"
HDL_TAP"TRUE";
"B \NAC \NWC"4;
"S \NAC"
BN"4"13;
%"TAP"
"1","(-5725,1950)","2","mstr_standard","I91";
;
CDS_LIB"mstr_standard"
BODY_TYPE"PLUMBING"
HDL_TAP"TRUE";
"B \NAC \NWC"4;
"S \NAC"
BN"6"15;
%"TAP"
"1","(-5725,3100)","2","mstr_standard","I92";
;
CDS_LIB"mstr_standard"
BODY_TYPE"PLUMBING"
HDL_TAP"TRUE";
"B \NAC \NWC"4;
"S \NAC"
BN"8"23;
%"TAP"
"1","(-5725,3250)","2","mstr_standard","I93";
;
CDS_LIB"mstr_standard"
BODY_TYPE"PLUMBING"
HDL_TAP"TRUE";
"B \NAC \NWC"4;
"S \NAC"
BN"11"6;
%"TAP"
"1","(-5725,3300)","2","mstr_standard","I94";
;
CDS_LIB"mstr_standard"
BODY_TYPE"PLUMBING"
HDL_TAP"TRUE";
"B \NAC \NWC"4;
"S \NAC"
BN"12"26;
%"TAP"
"1","(-5725,3350)","2","mstr_standard","I95";
;
CDS_LIB"mstr_standard"
BODY_TYPE"PLUMBING"
HDL_TAP"TRUE";
"B \NAC \NWC"4;
"S \NAC"
BN"13"27;
%"TAP"
"1","(-5725,2400)","2","mstr_standard","I96";
;
CDS_LIB"mstr_standard"
BODY_TYPE"PLUMBING"
HDL_TAP"TRUE";
"B \NAC \NWC"4;
"S \NAC"
BN"15"41;
%"TAP"
"1","(-5725,2450)","2","mstr_standard","I97";
;
CDS_LIB"mstr_standard"
BODY_TYPE"PLUMBING"
HDL_TAP"TRUE";
"B \NAC \NWC"4;
"S \NAC"
BN"16"42;
%"TAP"
"1","(-5725,3650)","2","mstr_standard","I98";
;
CDS_LIB"mstr_standard"
BODY_TYPE"PLUMBING"
HDL_TAP"TRUE";
"B \NAC \NWC"4;
"S \NAC"
BN"19"33;
%"TAP"
"1","(-2950,1650)","0","mstr_standard","I99";
;
CDS_LIB"mstr_standard"
BODY_TYPE"PLUMBING"
HDL_TAP"TRUE";
"B \NAC \NWC"1;
"S \NAC"
BN"0"46;
END.
